(kicad_pcb
	(version 20260206)
	(generator "pcbnew")
	(generator_version "10.0")
	(general
		(thickness 1.6)
		(legacy_teardrops no)
	)
	(paper "A4")
	(title_block
		(title "Wiwynn_Tioga_Pass_MB.brd")
		(comment 1 "Tioga Pass / footprint 1893 of 4770 (EU4D4), pads 43-49 of 49")
	)
	(layers
		(0 "F.Cu" signal "TOP")
		(4 "In1.Cu" signal "L2GND")
		(6 "In2.Cu" signal "L3")
		(8 "In3.Cu" signal "L4GND")
		(10 "In4.Cu" signal "L5")
		(12 "In5.Cu" signal "L6GND")
		(14 "In6.Cu" signal "L7VCC")
		(16 "In7.Cu" signal "L8VCC")
		(18 "In8.Cu" signal "L9GND")
		(20 "In9.Cu" signal "L10")
		(22 "In10.Cu" signal "L11GND")
		(24 "In11.Cu" signal "L12")
		(26 "In12.Cu" signal "L13GND")
		(2 "B.Cu" signal "BOTTOM")
		(9 "F.Adhes" user "F.Adhesive")
		(11 "B.Adhes" user "B.Adhesive")
		(13 "F.Paste" user "Package Geometry/Pastemask Top")
		(15 "B.Paste" user "Package Geometry/Pastemask Bottom")
		(5 "F.SilkS" user "Ref Des/Silkscreen Top")
		(7 "B.SilkS" user "Ref Des/Silkscreen Bottom")
		(1 "F.Mask" user "Board Geometry/Soldermask Top")
		(3 "B.Mask" user "Board Geometry/Soldermask Bottom")
		(17 "Dwgs.User" user "User.Drawings")
		(19 "Cmts.User" user "User.Comments")
		(21 "Eco1.User" user "User.Eco1")
		(23 "Eco2.User" user "User.Eco2")
		(25 "Edge.Cuts" user "Board Geometry/Outline")
		(27 "Margin" user)
		(31 "F.CrtYd" user "Package Geometry/Place Bound Top")
		(29 "B.CrtYd" user "Package Geometry/Place Bound Bottom")
		(35 "F.Fab" user "Ref Des/Assembly Top")
		(33 "B.Fab" user "Ref Des/Assembly Bottom")
	)
	(footprint ""
		(layer "F.Cu")
		(at 184.277 -69.85)
		(property "Reference" "EU4D4"
			(at -7.4422 -3.32613 0)
			(unlocked yes)
			(layer "F.SilkS")
			(effects
				(font
					(size 0.7874 0.5842)
					(thickness 0.1524)
				)
				(justify left)
			)
		)
		(property "Value" ""
			(at 0 0 0)
			(layer "F.Fab")
			(effects
				(font
					(size 1.27 1.27)
				)
			)
		)
		(duplicate_pad_numbers_are_jumpers no)
		(pad "43" smd custom
			(at -0.199898 -2.8956)
			(size 0.0508 0.0508)
			(layers "F.Cu" "F.Mask" "F.Paste")
			(net "A_TSENSE_PVCCIN_CPU0")
			(options
				(clearance outline)
				(anchor circle)
			)
			(primitives
				(gr_poly
					(pts
						(arc
							(start 0.1016 0.254)
							(mid 0 0.3556)
							(end -0.1016 0.254)
						)
						(xy -0.1016 -0.3556) (xy 0.1016 -0.3556)
					)
					(width 0)
					(fill yes)
				)
			)
		)
		(pad "44" smd custom
			(at -0.599948 -2.8956)
			(size 0.0508 0.0508)
			(layers "F.Cu" "F.Mask" "F.Paste")
			(net "VR_PVCCIN_CPU0_XADDR1")
			(options
				(clearance outline)
				(anchor circle)
			)
			(primitives
				(gr_poly
					(pts
						(arc
							(start 0.1016 0.254)
							(mid 0 0.3556)
							(end -0.1016 0.254)
						)
						(xy -0.1016 -0.3556) (xy 0.1016 -0.3556)
					)
					(width 0)
					(fill yes)
				)
			)
		)
		(pad "45" smd custom
			(at -0.999998 -2.8956)
			(size 0.0508 0.0508)
			(layers "F.Cu" "F.Mask" "F.Paste")
			(net "VR_PVCCIN_CPU0_AVINSEN")
			(options
				(clearance outline)
				(anchor circle)
			)
			(primitives
				(gr_poly
					(pts
						(arc
							(start 0.1016 0.254)
							(mid 0 0.3556)
							(end -0.1016 0.254)
						)
						(xy -0.1016 -0.3556) (xy 0.1016 -0.3556)
					)
					(width 0)
					(fill yes)
				)
			)
		)
		(pad "46" smd custom
			(at -1.400048 -2.8956)
			(size 0.0508 0.0508)
			(layers "F.Cu" "F.Mask" "F.Paste")
			(net "Net_217")
			(options
				(clearance outline)
				(anchor circle)
			)
			(primitives
				(gr_poly
					(pts
						(arc
							(start 0.1016 0.254)
							(mid 0 0.3556)
							(end -0.1016 0.254)
						)
						(xy -0.1016 -0.3556) (xy 0.1016 -0.3556)
					)
					(width 0)
					(fill yes)
				)
			)
		)
		(pad "47" smd custom
			(at -1.800098 -2.8956)
			(size 0.0508 0.0508)
			(layers "F.Cu" "F.Mask" "F.Paste")
			(net "VR_PVCCIN_CPU0_VDD")
			(options
				(clearance outline)
				(anchor circle)
			)
			(primitives
				(gr_poly
					(pts
						(arc
							(start 0.1016 0.254)
							(mid 0 0.3556)
							(end -0.1016 0.254)
						)
						(xy -0.1016 -0.3556) (xy 0.1016 -0.3556)
					)
					(width 0)
					(fill yes)
				)
			)
		)
		(pad "48" smd custom
			(at -2.199894 -2.8956)
			(size 0.0508 0.0508)
			(layers "F.Cu" "F.Mask" "F.Paste")
			(net "VR_PVCCIN_CPU0_VD12")
			(options
				(clearance outline)
				(anchor circle)
			)
			(primitives
				(gr_poly
					(pts
						(arc
							(start 0.1016 0.254)
							(mid 0 0.3556)
							(end -0.1016 0.254)
						)
						(xy -0.1016 -0.3556) (xy 0.1016 -0.3556)
					)
					(width 0)
					(fill yes)
				)
			)
		)
		(pad "49" smd rect
			(at 0 0)
			(size 3.6068 3.6068)
			(layers "F.Cu" "F.Mask" "F.Paste")
			(net "GND")
		)
	)
)
